# TIMECARD (Time Appliance Project (Time Card)) — schematic netlist excerpt (pin names and nets, part order shuffled) for the footprints in the layout excerpt that follows; sources: Cadence DE-HDL packaged netlist, KiCad conversion of R4006-B0001-02_R01.brd

R122  RESISTOR  49.9OHM 1%  pkg SMC_0402R_H016  page 23 : \1\ = BF_SMA3_SIG_IO_CONN ; \2\ = SMA3_SIG_IO_CONN
R362  RESISTOR  33OHM 1%  pkg SMC_0402R_H016  page 11 : \1\ = FPGA_FCS_B ; \2\ = FPGA_FLASH_CS_N

(kicad_pcb
	(version 20260206)
	(generator "pcbnew")
	(generator_version "10.0")
	(general
		(thickness 1.6)
		(legacy_teardrops no)
	)
	(paper "A4")
	(title_block
		(title "timecard-production-celestica-r4006 — R4006-B0001-02_R01.brd")
		(comment 1 "Time Appliance Project (Time Card) / footprints 417-419 of 1113")
	)
	(layers
		(0 "F.Cu" signal "TOP")
		(4 "In1.Cu" signal "L02_GND1")
		(6 "In2.Cu" signal "L03_SIG1")
		(8 "In3.Cu" signal "L04_GND2")
		(10 "In4.Cu" signal "L05_VCC1")
		(12 "In5.Cu" signal "L06_VCC2")
		(14 "In6.Cu" signal "L07_GND3")
		(16 "In7.Cu" signal "L08_SIG2")
		(18 "In8.Cu" signal "L09_GND4")
		(2 "B.Cu" signal "BOTTOM")
		(9 "F.Adhes" user "F.Adhesive")
		(11 "B.Adhes" user "B.Adhesive")
		(13 "F.Paste" user "Package Geometry/Pastemask Top")
		(15 "B.Paste" user "Package Geometry/Pastemask Bottom")
		(5 "F.SilkS" user "Ref Des/Silkscreen Top")
		(7 "B.SilkS" user "Ref Des/Silkscreen Bottom")
		(1 "F.Mask" user "Board Geometry/Soldermask Top")
		(3 "B.Mask" user "Board Geometry/Soldermask Bottom")
		(17 "Dwgs.User" user "User.Drawings")
		(19 "Cmts.User" user "User.Comments")
		(21 "Eco1.User" user "User.Eco1")
		(23 "Eco2.User" user "User.Eco2")
		(25 "Edge.Cuts" user "Board Geometry/Outline")
		(27 "Margin" user)
		(31 "F.CrtYd" user "Package Geometry/Place Bound Top")
		(29 "B.CrtYd" user "Package Geometry/Place Bound Bottom")
		(35 "F.Fab" user "Ref Des/Assembly Top")
		(33 "B.Fab" user "Ref Des/Assembly Bottom")
	)
	(footprint ""
		(layer "F.Cu")
		(at 118.11 -58.928 90)
		(property "Reference" "R362"
			(at -0.127 1.30937 90)
			(unlocked yes)
			(layer "F.SilkS")
			(effects
				(font
					(size 0.7874 0.5842)
					(thickness 0.1524)
				)
			)
		)
		(property "Value" "VAL*"
			(at 0.02032 2.13233 90)
			(unlocked yes)
			(layer "F.Fab")
			(hide yes)
			(effects
				(font
					(size 0.7874 0.5842)
					(thickness 0.1524)
				)
			)
		)
		(property "Tolerance" "TOL*"
			(at 0.044704 3.05435 90)
			(unlocked yes)
			(layer "Cmts.User")
			(hide yes)
			(effects
				(font
					(size 0.7874 0.5842)
					(thickness 0.1524)
				)
			)
		)
		(property "User Part Number" "PARTNUM*"
			(at 0.02032 4.024884 90)
			(unlocked yes)
			(layer "Cmts.User")
			(hide yes)
			(effects
				(font
					(size 0.7874 0.5842)
					(thickness 0.1524)
				)
			)
		)
		(property "Device Type" "RESISTOR-G155-133R0-01,33OHM,1%"
			(at 0.008382 1.210564 90)
			(unlocked yes)
			(layer "F.Fab")
			(hide yes)
			(effects
				(font
					(size 0.7874 0.5842)
					(thickness 0.1524)
				)
			)
		)
		(duplicate_pad_numbers_are_jumpers no)
		(fp_line
			(start 1.143 -0.5588)
			(end -1.143 -0.5588)
			(stroke
				(width 0.1)
				(type default)
			)
			(layer "F.SilkS")
		)
		(fp_line
			(start -1.143 -0.5588)
			(end -1.143 0.5588)
			(stroke
				(width 0.1)
				(type default)
			)
			(layer "F.SilkS")
		)
		(fp_line
			(start 1.143 0.5588)
			(end 1.143 -0.5588)
			(stroke
				(width 0.1)
				(type default)
			)
			(layer "F.SilkS")
		)
		(fp_line
			(start -1.143 0.5588)
			(end 1.143 0.5588)
			(stroke
				(width 0.1)
				(type default)
			)
			(layer "F.SilkS")
		)
		(fp_poly
			(pts
				(xy -1.143 0.5588) (xy 1.143 0.5588) (xy 1.143 -0.5588) (xy -1.143 -0.5588)
			)
			(stroke
				(width 0)
				(type default)
			)
			(fill no)
			(layer "F.CrtYd")
		)
		(fp_line
			(start 0.508 -0.3048)
			(end -0.508 -0.3048)
			(stroke
				(width 0.1)
				(type default)
			)
			(layer "F.Fab")
		)
		(fp_line
			(start -0.508 -0.3048)
			(end -0.508 0.3048)
			(stroke
				(width 0.1)
				(type default)
			)
			(layer "F.Fab")
		)
		(fp_line
			(start 0.508 0.3048)
			(end 0.508 -0.3048)
			(stroke
				(width 0.1)
				(type default)
			)
			(layer "F.Fab")
		)
		(fp_line
			(start -0.508 0.3048)
			(end 0.508 0.3048)
			(stroke
				(width 0.1)
				(type default)
			)
			(layer "F.Fab")
		)
		(pad "1" smd rect
			(at -0.5334 0 90)
			(size 0.7112 0.6096)
			(layers "F.Cu" "F.Mask" "F.Paste")
			(net "FPGA_FCS_B")
		)
		(pad "2" smd rect
			(at 0.5334 0 90)
			(size 0.7112 0.6096)
			(layers "F.Cu" "F.Mask" "F.Paste")
			(net "FPGA_FLASH_CS_N")
		)
		(zone
			(layer "F.Cu")
			(hatch none 0.5)
			(connect_pads
				(clearance 0)
			)
			(min_thickness 0.25)
			(keepout
				(tracks not_allowed)
				(vias allowed)
				(pads allowed)
				(copperpour not_allowed)
				(footprints allowed)
			)
			(placement
				(enabled no)
				(sheetname "")
			)
			(fill
				(thermal_gap 0.5)
				(thermal_bridge_width 0.5)
				(island_removal_mode 0)
			)
			(polygon
				(pts
					(xy 118.4148 -58.8518) (xy 118.4148 -59.0042) (xy 117.8052 -59.0042) (xy 117.8052 -58.8518)
				)
			)
		)
		(zone
			(layer "F.Cu")
			(hatch none 0.5)
			(connect_pads
				(clearance 0)
			)
			(min_thickness 0.25)
			(keepout
				(tracks allowed)
				(vias not_allowed)
				(pads allowed)
				(copperpour not_allowed)
				(footprints allowed)
			)
			(placement
				(enabled no)
				(sheetname "")
			)
			(fill
				(thermal_gap 0.5)
				(thermal_bridge_width 0.5)
				(island_removal_mode 0)
			)
			(polygon
				(pts
					(xy 118.4148 -58.8518) (xy 118.4148 -59.0042) (xy 117.8052 -59.0042) (xy 117.8052 -58.8518)
				)
			)
		)
	)
	(footprint ""
		(layer "F.Cu")
		(at 11.557 -28.06446 -90)
		(property "Reference" "R122"
			(at 0.50546 2.11963 90)
			(unlocked yes)
			(layer "F.SilkS")
			(effects
				(font
					(size 0.7874 0.5842)
					(thickness 0.1524)
				)
			)
		)
		(property "Value" "VAL*"
			(at 0.02032 2.13233 270)
			(unlocked yes)
			(layer "F.Fab")
			(hide yes)
			(effects
				(font
					(size 0.7874 0.5842)
					(thickness 0.1524)
				)
			)
		)
		(property "Tolerance" "TOL*"
			(at 0.044704 3.05435 270)
			(unlocked yes)
			(layer "Cmts.User")
			(hide yes)
			(effects
				(font
					(size 0.7874 0.5842)
					(thickness 0.1524)
				)
			)
		)
		(property "User Part Number" "PARTNUM*"
			(at 0.02032 4.024884 270)
			(unlocked yes)
			(layer "Cmts.User")
			(hide yes)
			(effects
				(font
					(size 0.7874 0.5842)
					(thickness 0.1524)
				)
			)
		)
		(property "Device Type" "RESISTOR-G155-149R9-01,49.9OHMA"
			(at 0.008382 1.210564 270)
			(unlocked yes)
			(layer "F.Fab")
			(hide yes)
			(effects
				(font
					(size 0.7874 0.5842)
					(thickness 0.1524)
				)
			)
		)
		(duplicate_pad_numbers_are_jumpers no)
		(fp_line
			(start -1.143 0.5588)
			(end 1.143 0.5588)
			(stroke
				(width 0.1)
				(type default)
			)
			(layer "F.SilkS")
		)
		(fp_line
			(start 1.143 0.5588)
			(end 1.143 -0.5588)
			(stroke
				(width 0.1)
				(type default)
			)
			(layer "F.SilkS")
		)
		(fp_line
			(start -1.143 -0.5588)
			(end -1.143 0.5588)
			(stroke
				(width 0.1)
				(type default)
			)
			(layer "F.SilkS")
		)
		(fp_line
			(start 1.143 -0.5588)
			(end -1.143 -0.5588)
			(stroke
				(width 0.1)
				(type default)
			)
			(layer "F.SilkS")
		)
		(fp_poly
			(pts
				(xy -1.143 0.5588) (xy 1.143 0.5588) (xy 1.143 -0.5588) (xy -1.143 -0.5588)
			)
			(stroke
				(width 0)
				(type default)
			)
			(fill no)
			(layer "F.CrtYd")
		)
		(fp_line
			(start -0.508 0.3048)
			(end 0.508 0.3048)
			(stroke
				(width 0.1)
				(type default)
			)
			(layer "F.Fab")
		)
		(fp_line
			(start 0.508 0.3048)
			(end 0.508 -0.3048)
			(stroke
				(width 0.1)
				(type default)
			)
			(layer "F.Fab")
		)
		(fp_line
			(start -0.508 -0.3048)
			(end -0.508 0.3048)
			(stroke
				(width 0.1)
				(type default)
			)
			(layer "F.Fab")
		)
		(fp_line
			(start 0.508 -0.3048)
			(end -0.508 -0.3048)
			(stroke
				(width 0.1)
				(type default)
			)
			(layer "F.Fab")
		)
		(pad "1" smd rect
			(at -0.5334 0 270)
			(size 0.7112 0.6096)
			(layers "F.Cu" "F.Mask" "F.Paste")
			(net "BF_SMA3_SIG_IO_CONN")
		)
		(pad "2" smd rect
			(at 0.5334 0 270)
			(size 0.7112 0.6096)
			(layers "F.Cu" "F.Mask" "F.Paste")
			(net "SMA3_SIG_IO_CONN")
		)
		(zone
			(layer "F.Cu")
			(hatch none 0.5)
			(connect_pads
				(clearance 0)
			)
			(min_thickness 0.25)
			(keepout
				(tracks allowed)
				(vias not_allowed)
				(pads allowed)
				(copperpour not_allowed)
				(footprints allowed)
			)
			(placement
				(enabled no)
				(sheetname "")
			)
			(fill
				(thermal_gap 0.5)
				(thermal_bridge_width 0.5)
				(island_removal_mode 0)
			)
			(polygon
				(pts
					(xy 11.2522 -28.14066) (xy 11.2522 -27.98826) (xy 11.8618 -27.98826) (xy 11.8618 -28.14066)
				)
			)
		)
		(zone
			(layer "F.Cu")
			(hatch none 0.5)
			(connect_pads
				(clearance 0)
			)
			(min_thickness 0.25)
			(keepout
				(tracks not_allowed)
				(vias allowed)
				(pads allowed)
				(copperpour not_allowed)
				(footprints allowed)
			)
			(placement
				(enabled no)
				(sheetname "")
			)
			(fill
				(thermal_gap 0.5)
				(thermal_bridge_width 0.5)
				(island_removal_mode 0)
			)
			(polygon
				(pts
					(xy 11.2522 -28.14066) (xy 11.2522 -27.98826) (xy 11.8618 -27.98826) (xy 11.8618 -28.14066)
				)
			)
		)
	)
	(footprint ""
		(layer "F.Cu")
		(at 56.388 -129.032)
		(property "Reference" "SP81"
			(at 0 0 0)
			(layer "F.SilkS")
			(hide yes)
			(effects
				(font
					(size 1.27 1.27)
				)
			)
		)
		(property "Value" ""
			(at 0 0 0)
			(layer "F.Fab")
			(effects
				(font
					(size 1.27 1.27)
				)
			)
		)
		(duplicate_pad_numbers_are_jumpers no)
	)
)
